(kicad_pcb
	(version 20260206)
	(generator "pcbnew")
	(generator_version "10.0")
	(general
		(thickness 1.6)
		(legacy_teardrops no)
	)
	(paper "A4")
	(title_block
		(title "01162023_DA0F0TEBIF0_F0T_Expander_BD_F_brd_V02_OCP.brd")
		(comment 1 "Grand Teton / footprints 6202-6209 of 9728")
	)
	(layers
		(0 "F.Cu" signal "TOP")
		(4 "In1.Cu" signal "GND")
		(6 "In2.Cu" signal "VCC")
		(8 "In3.Cu" signal "VCC1")
		(10 "In4.Cu" signal "GND1")
		(12 "In5.Cu" signal "IN1")
		(14 "In6.Cu" signal "GND2")
		(16 "In7.Cu" signal "IN2")
		(18 "In8.Cu" signal "GND3")
		(20 "In9.Cu" signal "IN3")
		(22 "In10.Cu" signal "GND4")
		(24 "In11.Cu" signal "IN4")
		(26 "In12.Cu" signal "GND5")
		(28 "In13.Cu" signal "IN5")
		(30 "In14.Cu" signal "GND6")
		(32 "In15.Cu" signal "IN6")
		(34 "In16.Cu" signal "GND7")
		(2 "B.Cu" signal "BOTTOM")
		(9 "F.Adhes" user "F.Adhesive")
		(11 "B.Adhes" user "B.Adhesive")
		(13 "F.Paste" user "Package Geometry/Pastemask Top")
		(15 "B.Paste" user "Package Geometry/Pastemask Bottom")
		(5 "F.SilkS" user "Ref Des/Silkscreen Top")
		(7 "B.SilkS" user "Ref Des/Silkscreen Bottom")
		(1 "F.Mask" user "Board Geometry/Soldermask Top")
		(3 "B.Mask" user "Board Geometry/Soldermask Bottom")
		(17 "Dwgs.User" user "User.Drawings")
		(19 "Cmts.User" user "User.Comments")
		(21 "Eco1.User" user "User.Eco1")
		(23 "Eco2.User" user "User.Eco2")
		(25 "Edge.Cuts" user "Board Geometry/Outline")
		(27 "Margin" user)
		(31 "F.CrtYd" user "Package Geometry/Place Bound Top")
		(29 "B.CrtYd" user "Package Geometry/Place Bound Bottom")
		(35 "F.Fab" user "Ref Des/Assembly Top")
		(33 "B.Fab" user "Ref Des/Assembly Bottom")
	)
	(footprint ""
		(layer "F.Cu")
		(at 419.05301 -221.32163 180)
		(property "Reference" "R6615"
			(at 0 0 180)
			(layer "F.SilkS")
			(hide yes)
			(effects
				(font
					(size 1.27 1.27)
				)
			)
		)
		(property "Value" ""
			(at 0 0 180)
			(layer "F.Fab")
			(effects
				(font
					(size 1.27 1.27)
				)
			)
		)
		(duplicate_pad_numbers_are_jumpers no)
		(fp_line
			(start 0.7874 0.4064)
			(end -0.7874 0.4064)
			(stroke
				(width 0.1524)
				(type default)
			)
			(layer "F.SilkS")
		)
		(fp_line
			(start 0.7874 -0.4064)
			(end 0.7874 0.4064)
			(stroke
				(width 0.1524)
				(type default)
			)
			(layer "F.SilkS")
		)
		(fp_line
			(start -0.7874 0.4064)
			(end -0.7874 -0.4064)
			(stroke
				(width 0.1524)
				(type default)
			)
			(layer "F.SilkS")
		)
		(fp_line
			(start -0.7874 -0.4064)
			(end 0.7874 -0.4064)
			(stroke
				(width 0.1524)
				(type default)
			)
			(layer "F.SilkS")
		)
		(fp_line
			(start 0.67945 0.3048)
			(end 0.120396 0.3048)
			(stroke
				(width 0.1)
				(type default)
			)
			(layer "F.Fab")
		)
		(fp_line
			(start 0.67945 -0.3048)
			(end 0.67945 0.3048)
			(stroke
				(width 0.1)
				(type default)
			)
			(layer "F.Fab")
		)
		(fp_line
			(start 0.12065 -0.2794)
			(end 0.12065 -0.3048)
			(stroke
				(width 0.1)
				(type default)
			)
			(layer "F.Fab")
		)
		(fp_line
			(start 0.12065 -0.3048)
			(end 0.67945 -0.3048)
			(stroke
				(width 0.1)
				(type default)
			)
			(layer "F.Fab")
		)
		(fp_line
			(start 0.120396 0.3048)
			(end 0.120396 0.2794)
			(stroke
				(width 0.1)
				(type default)
			)
			(layer "F.Fab")
		)
		(fp_line
			(start 0.120396 0.2794)
			(end -0.12065 0.2794)
			(stroke
				(width 0.1)
				(type default)
			)
			(layer "F.Fab")
		)
		(fp_line
			(start -0.12065 0.3048)
			(end -0.67945 0.3048)
			(stroke
				(width 0.1)
				(type default)
			)
			(layer "F.Fab")
		)
		(fp_line
			(start -0.12065 0.2794)
			(end -0.12065 0.3048)
			(stroke
				(width 0.1)
				(type default)
			)
			(layer "F.Fab")
		)
		(fp_line
			(start -0.12065 -0.2794)
			(end 0.12065 -0.2794)
			(stroke
				(width 0.1)
				(type default)
			)
			(layer "F.Fab")
		)
		(fp_line
			(start -0.12065 -0.305054)
			(end -0.12065 -0.2794)
			(stroke
				(width 0.1)
				(type default)
			)
			(layer "F.Fab")
		)
		(fp_line
			(start -0.67945 0.3048)
			(end -0.67945 -0.305054)
			(stroke
				(width 0.1)
				(type default)
			)
			(layer "F.Fab")
		)
		(fp_line
			(start -0.67945 -0.305054)
			(end -0.12065 -0.305054)
			(stroke
				(width 0.1)
				(type default)
			)
			(layer "F.Fab")
		)
		(pad "1" smd circle
			(at -0.40005 0 180)
			(size 0 0)
			(layers "F.Cu" "F.Mask" "F.Paste")
			(net "UART_PEX0_SDB_R_RX")
		)
		(pad "2" smd circle
			(at 0.40005 0 180)
			(size 0 0)
			(layers "F.Cu" "F.Mask" "F.Paste")
			(net "UART_PEX0_SDB_R1_RX")
		)
	)
	(footprint ""
		(layer "F.Cu")
		(at 271.480534 -103.803196)
		(property "Reference" "C482"
			(at 0 0 0)
			(layer "F.SilkS")
			(hide yes)
			(effects
				(font
					(size 1.27 1.27)
				)
			)
		)
		(property "Value" ""
			(at 0 0 0)
			(layer "F.Fab")
			(effects
				(font
					(size 1.27 1.27)
				)
			)
		)
		(duplicate_pad_numbers_are_jumpers no)
		(fp_line
			(start -0.299974 -0.150114)
			(end 0.299974 -0.150114)
			(stroke
				(width 0.1)
				(type default)
			)
			(layer "F.Fab")
		)
		(fp_line
			(start -0.299974 0.150114)
			(end -0.299974 -0.150114)
			(stroke
				(width 0.1)
				(type default)
			)
			(layer "F.Fab")
		)
		(fp_line
			(start 0.299974 -0.150114)
			(end 0.299974 0.150114)
			(stroke
				(width 0.1)
				(type default)
			)
			(layer "F.Fab")
		)
		(fp_line
			(start 0.299974 0.150114)
			(end -0.299974 0.150114)
			(stroke
				(width 0.1)
				(type default)
			)
			(layer "F.Fab")
		)
		(pad "1" smd rect
			(at -0.2667 0)
			(size 0.3048 0.381)
			(layers "F.Cu" "F.Mask" "F.Paste")
			(net "P5E_PEX2_STN1_TX_DN<18>")
		)
		(pad "2" smd rect
			(at 0.2667 0)
			(size 0.3048 0.381)
			(layers "F.Cu" "F.Mask" "F.Paste")
			(net "P5E_PEX2_STN1_TX_C_DN<18>")
		)
	)
	(footprint ""
		(layer "F.Cu")
		(at 336.042 -184.023 180)
		(property "Reference" "R4746"
			(at 0 0 180)
			(layer "F.SilkS")
			(hide yes)
			(effects
				(font
					(size 1.27 1.27)
				)
			)
		)
		(property "Value" ""
			(at 0 0 180)
			(layer "F.Fab")
			(effects
				(font
					(size 1.27 1.27)
				)
			)
		)
		(duplicate_pad_numbers_are_jumpers no)
		(fp_line
			(start 0.7874 0.4064)
			(end -0.7874 0.4064)
			(stroke
				(width 0.1524)
				(type default)
			)
			(layer "F.SilkS")
		)
		(fp_line
			(start 0.7874 -0.4064)
			(end 0.7874 0.4064)
			(stroke
				(width 0.1524)
				(type default)
			)
			(layer "F.SilkS")
		)
		(fp_line
			(start -0.7874 0.4064)
			(end -0.7874 -0.4064)
			(stroke
				(width 0.1524)
				(type default)
			)
			(layer "F.SilkS")
		)
		(fp_line
			(start -0.7874 -0.4064)
			(end 0.7874 -0.4064)
			(stroke
				(width 0.1524)
				(type default)
			)
			(layer "F.SilkS")
		)
		(fp_line
			(start 0.67945 0.3048)
			(end 0.120396 0.3048)
			(stroke
				(width 0.1)
				(type default)
			)
			(layer "F.Fab")
		)
		(fp_line
			(start 0.67945 -0.3048)
			(end 0.67945 0.3048)
			(stroke
				(width 0.1)
				(type default)
			)
			(layer "F.Fab")
		)
		(fp_line
			(start 0.12065 -0.2794)
			(end 0.12065 -0.3048)
			(stroke
				(width 0.1)
				(type default)
			)
			(layer "F.Fab")
		)
		(fp_line
			(start 0.12065 -0.3048)
			(end 0.67945 -0.3048)
			(stroke
				(width 0.1)
				(type default)
			)
			(layer "F.Fab")
		)
		(fp_line
			(start 0.120396 0.3048)
			(end 0.120396 0.2794)
			(stroke
				(width 0.1)
				(type default)
			)
			(layer "F.Fab")
		)
		(fp_line
			(start 0.120396 0.2794)
			(end -0.12065 0.2794)
			(stroke
				(width 0.1)
				(type default)
			)
			(layer "F.Fab")
		)
		(fp_line
			(start -0.12065 0.3048)
			(end -0.67945 0.3048)
			(stroke
				(width 0.1)
				(type default)
			)
			(layer "F.Fab")
		)
		(fp_line
			(start -0.12065 0.2794)
			(end -0.12065 0.3048)
			(stroke
				(width 0.1)
				(type default)
			)
			(layer "F.Fab")
		)
		(fp_line
			(start -0.12065 -0.2794)
			(end 0.12065 -0.2794)
			(stroke
				(width 0.1)
				(type default)
			)
			(layer "F.Fab")
		)
		(fp_line
			(start -0.12065 -0.305054)
			(end -0.12065 -0.2794)
			(stroke
				(width 0.1)
				(type default)
			)
			(layer "F.Fab")
		)
		(fp_line
			(start -0.67945 0.3048)
			(end -0.67945 -0.305054)
			(stroke
				(width 0.1)
				(type default)
			)
			(layer "F.Fab")
		)
		(fp_line
			(start -0.67945 -0.305054)
			(end -0.12065 -0.305054)
			(stroke
				(width 0.1)
				(type default)
			)
			(layer "F.Fab")
		)
		(pad "1" smd circle
			(at -0.40005 0 180)
			(size 0 0)
			(layers "F.Cu" "F.Mask" "F.Paste")
			(net "PCA9555_0_PEX2_A2")
		)
		(pad "2" smd circle
			(at 0.40005 0 180)
			(size 0 0)
			(layers "F.Cu" "F.Mask" "F.Paste")
			(net "P3V3_AUX")
		)
	)
	(footprint ""
		(layer "F.Cu")
		(at 457.817728 -258.331208 -90)
		(property "Reference" "R6555"
			(at 0 0 270)
			(layer "F.SilkS")
			(hide yes)
			(effects
				(font
					(size 1.27 1.27)
				)
			)
		)
		(property "Value" ""
			(at 0 0 270)
			(layer "F.Fab")
			(effects
				(font
					(size 1.27 1.27)
				)
			)
		)
		(duplicate_pad_numbers_are_jumpers no)
		(fp_line
			(start -0.7874 0.4064)
			(end -0.7874 -0.4064)
			(stroke
				(width 0.1524)
				(type default)
			)
			(layer "F.SilkS")
		)
		(fp_line
			(start 0.7874 0.4064)
			(end -0.7874 0.4064)
			(stroke
				(width 0.1524)
				(type default)
			)
			(layer "F.SilkS")
		)
		(fp_line
			(start -0.7874 -0.4064)
			(end 0.7874 -0.4064)
			(stroke
				(width 0.1524)
				(type default)
			)
			(layer "F.SilkS")
		)
		(fp_line
			(start 0.7874 -0.4064)
			(end 0.7874 0.4064)
			(stroke
				(width 0.1524)
				(type default)
			)
			(layer "F.SilkS")
		)
		(fp_line
			(start -0.67945 0.3048)
			(end -0.67945 -0.305054)
			(stroke
				(width 0.1)
				(type default)
			)
			(layer "F.Fab")
		)
		(fp_line
			(start -0.12065 0.3048)
			(end -0.67945 0.3048)
			(stroke
				(width 0.1)
				(type default)
			)
			(layer "F.Fab")
		)
		(fp_line
			(start 0.120396 0.3048)
			(end 0.120396 0.2794)
			(stroke
				(width 0.1)
				(type default)
			)
			(layer "F.Fab")
		)
		(fp_line
			(start 0.67945 0.3048)
			(end 0.120396 0.3048)
			(stroke
				(width 0.1)
				(type default)
			)
			(layer "F.Fab")
		)
		(fp_line
			(start -0.12065 0.2794)
			(end -0.12065 0.3048)
			(stroke
				(width 0.1)
				(type default)
			)
			(layer "F.Fab")
		)
		(fp_line
			(start 0.120396 0.2794)
			(end -0.12065 0.2794)
			(stroke
				(width 0.1)
				(type default)
			)
			(layer "F.Fab")
		)
		(fp_line
			(start -0.12065 -0.2794)
			(end 0.12065 -0.2794)
			(stroke
				(width 0.1)
				(type default)
			)
			(layer "F.Fab")
		)
		(fp_line
			(start 0.12065 -0.2794)
			(end 0.12065 -0.3048)
			(stroke
				(width 0.1)
				(type default)
			)
			(layer "F.Fab")
		)
		(fp_line
			(start 0.12065 -0.3048)
			(end 0.67945 -0.3048)
			(stroke
				(width 0.1)
				(type default)
			)
			(layer "F.Fab")
		)
		(fp_line
			(start 0.67945 -0.3048)
			(end 0.67945 0.3048)
			(stroke
				(width 0.1)
				(type default)
			)
			(layer "F.Fab")
		)
		(fp_line
			(start -0.67945 -0.305054)
			(end -0.12065 -0.305054)
			(stroke
				(width 0.1)
				(type default)
			)
			(layer "F.Fab")
		)
		(fp_line
			(start -0.12065 -0.305054)
			(end -0.12065 -0.2794)
			(stroke
				(width 0.1)
				(type default)
			)
			(layer "F.Fab")
		)
		(pad "1" smd circle
			(at -0.40005 0 270)
			(size 0 0)
			(layers "F.Cu" "F.Mask" "F.Paste")
			(net "P1V25_SERDES_VDDPLL_PEX3")
		)
		(pad "2" smd circle
			(at 0.40005 0 270)
			(size 0 0)
			(layers "F.Cu" "F.Mask" "F.Paste")
			(net "P1V25_SERDES_VDDPLL_PEX3_C4")
		)
	)
	(footprint ""
		(layer "F.Cu")
		(at 130.430016 -193.143378 -90)
		(property "Reference" "R6668"
			(at 0 0 270)
			(layer "F.SilkS")
			(hide yes)
			(effects
				(font
					(size 1.27 1.27)
				)
			)
		)
		(property "Value" ""
			(at 0 0 270)
			(layer "F.Fab")
			(effects
				(font
					(size 1.27 1.27)
				)
			)
		)
		(duplicate_pad_numbers_are_jumpers no)
		(fp_line
			(start -0.7874 0.4064)
			(end -0.7874 -0.4064)
			(stroke
				(width 0.1524)
				(type default)
			)
			(layer "F.SilkS")
		)
		(fp_line
			(start 0.7874 0.4064)
			(end -0.7874 0.4064)
			(stroke
				(width 0.1524)
				(type default)
			)
			(layer "F.SilkS")
		)
		(fp_line
			(start -0.7874 -0.4064)
			(end 0.7874 -0.4064)
			(stroke
				(width 0.1524)
				(type default)
			)
			(layer "F.SilkS")
		)
		(fp_line
			(start 0.7874 -0.4064)
			(end 0.7874 0.4064)
			(stroke
				(width 0.1524)
				(type default)
			)
			(layer "F.SilkS")
		)
		(fp_line
			(start -0.67945 0.3048)
			(end -0.67945 -0.305054)
			(stroke
				(width 0.1)
				(type default)
			)
			(layer "F.Fab")
		)
		(fp_line
			(start -0.12065 0.3048)
			(end -0.67945 0.3048)
			(stroke
				(width 0.1)
				(type default)
			)
			(layer "F.Fab")
		)
		(fp_line
			(start 0.120396 0.3048)
			(end 0.120396 0.2794)
			(stroke
				(width 0.1)
				(type default)
			)
			(layer "F.Fab")
		)
		(fp_line
			(start 0.67945 0.3048)
			(end 0.120396 0.3048)
			(stroke
				(width 0.1)
				(type default)
			)
			(layer "F.Fab")
		)
		(fp_line
			(start -0.12065 0.2794)
			(end -0.12065 0.3048)
			(stroke
				(width 0.1)
				(type default)
			)
			(layer "F.Fab")
		)
		(fp_line
			(start 0.120396 0.2794)
			(end -0.12065 0.2794)
			(stroke
				(width 0.1)
				(type default)
			)
			(layer "F.Fab")
		)
		(fp_line
			(start -0.12065 -0.2794)
			(end 0.12065 -0.2794)
			(stroke
				(width 0.1)
				(type default)
			)
			(layer "F.Fab")
		)
		(fp_line
			(start 0.12065 -0.2794)
			(end 0.12065 -0.3048)
			(stroke
				(width 0.1)
				(type default)
			)
			(layer "F.Fab")
		)
		(fp_line
			(start 0.12065 -0.3048)
			(end 0.67945 -0.3048)
			(stroke
				(width 0.1)
				(type default)
			)
			(layer "F.Fab")
		)
		(fp_line
			(start 0.67945 -0.3048)
			(end 0.67945 0.3048)
			(stroke
				(width 0.1)
				(type default)
			)
			(layer "F.Fab")
		)
		(fp_line
			(start -0.67945 -0.305054)
			(end -0.12065 -0.305054)
			(stroke
				(width 0.1)
				(type default)
			)
			(layer "F.Fab")
		)
		(fp_line
			(start -0.12065 -0.305054)
			(end -0.12065 -0.2794)
			(stroke
				(width 0.1)
				(type default)
			)
			(layer "F.Fab")
		)
		(pad "1" smd circle
			(at -0.40005 0 270)
			(size 0 0)
			(layers "F.Cu" "F.Mask" "F.Paste")
			(net "NIC7_CLK_EN_BUF_N")
		)
		(pad "2" smd circle
			(at 0.40005 0 270)
			(size 0 0)
			(layers "F.Cu" "F.Mask" "F.Paste")
			(net "NIC7_CLK_EN_BUF_R_N")
		)
	)
	(footprint ""
		(layer "F.Cu")
		(at 268.838426 -111.895382)
		(property "Reference" "C471"
			(at 0 0 0)
			(layer "F.SilkS")
			(hide yes)
			(effects
				(font
					(size 1.27 1.27)
				)
			)
		)
		(property "Value" ""
			(at 0 0 0)
			(layer "F.Fab")
			(effects
				(font
					(size 1.27 1.27)
				)
			)
		)
		(duplicate_pad_numbers_are_jumpers no)
		(fp_line
			(start -0.299974 -0.150114)
			(end 0.299974 -0.150114)
			(stroke
				(width 0.1)
				(type default)
			)
			(layer "F.Fab")
		)
		(fp_line
			(start -0.299974 0.150114)
			(end -0.299974 -0.150114)
			(stroke
				(width 0.1)
				(type default)
			)
			(layer "F.Fab")
		)
		(fp_line
			(start 0.299974 -0.150114)
			(end 0.299974 0.150114)
			(stroke
				(width 0.1)
				(type default)
			)
			(layer "F.Fab")
		)
		(fp_line
			(start 0.299974 0.150114)
			(end -0.299974 0.150114)
			(stroke
				(width 0.1)
				(type default)
			)
			(layer "F.Fab")
		)
		(pad "1" smd rect
			(at -0.2667 0)
			(size 0.3048 0.381)
			(layers "F.Cu" "F.Mask" "F.Paste")
			(net "P5E_PEX2_STN1_TX_DN<23>")
		)
		(pad "2" smd rect
			(at 0.2667 0)
			(size 0.3048 0.381)
			(layers "F.Cu" "F.Mask" "F.Paste")
			(net "P5E_PEX2_STN1_TX_C_DN<23>")
		)
	)
	(footprint ""
		(layer "F.Cu")
		(at 420.73449 -33.631886 180)
		(property "Reference" "C715"
			(at 0 0 180)
			(layer "F.SilkS")
			(hide yes)
			(effects
				(font
					(size 1.27 1.27)
				)
			)
		)
		(property "Value" ""
			(at 0 0 180)
			(layer "F.Fab")
			(effects
				(font
					(size 1.27 1.27)
				)
			)
		)
		(duplicate_pad_numbers_are_jumpers no)
		(fp_line
			(start 0.299974 0.150114)
			(end -0.299974 0.150114)
			(stroke
				(width 0.1)
				(type default)
			)
			(layer "F.Fab")
		)
		(fp_line
			(start 0.299974 -0.150114)
			(end 0.299974 0.150114)
			(stroke
				(width 0.1)
				(type default)
			)
			(layer "F.Fab")
		)
		(fp_line
			(start -0.299974 0.150114)
			(end -0.299974 -0.150114)
			(stroke
				(width 0.1)
				(type default)
			)
			(layer "F.Fab")
		)
		(fp_line
			(start -0.299974 -0.150114)
			(end 0.299974 -0.150114)
			(stroke
				(width 0.1)
				(type default)
			)
			(layer "F.Fab")
		)
		(pad "1" smd rect
			(at -0.2667 0 180)
			(size 0.3048 0.381)
			(layers "F.Cu" "F.Mask" "F.Paste")
			(net "P5E_PEX3_STN2_TX_DN<39>")
		)
		(pad "2" smd rect
			(at 0.2667 0 180)
			(size 0.3048 0.381)
			(layers "F.Cu" "F.Mask" "F.Paste")
			(net "P5E_PEX3_STN2_TX_C_DN<39>")
		)
	)
	(footprint ""
		(layer "F.Cu")
		(at 366.955578 -81.498694 180)
		(property "Reference" "R1616"
			(at 0 0 180)
			(layer "F.SilkS")
			(hide yes)
			(effects
				(font
					(size 1.27 1.27)
				)
			)
		)
		(property "Value" ""
			(at 0 0 180)
			(layer "F.Fab")
			(effects
				(font
					(size 1.27 1.27)
				)
			)
		)
		(duplicate_pad_numbers_are_jumpers no)
		(fp_line
			(start 0.7874 0.4064)
			(end -0.7874 0.4064)
			(stroke
				(width 0.1524)
				(type default)
			)
			(layer "F.SilkS")
		)
		(fp_line
			(start 0.7874 -0.4064)
			(end 0.7874 0.4064)
			(stroke
				(width 0.1524)
				(type default)
			)
			(layer "F.SilkS")
		)
		(fp_line
			(start -0.7874 0.4064)
			(end -0.7874 -0.4064)
			(stroke
				(width 0.1524)
				(type default)
			)
			(layer "F.SilkS")
		)
		(fp_line
			(start -0.7874 -0.4064)
			(end 0.7874 -0.4064)
			(stroke
				(width 0.1524)
				(type default)
			)
			(layer "F.SilkS")
		)
		(fp_line
			(start 0.67945 0.3048)
			(end 0.120396 0.3048)
			(stroke
				(width 0.1)
				(type default)
			)
			(layer "F.Fab")
		)
		(fp_line
			(start 0.67945 -0.3048)
			(end 0.67945 0.3048)
			(stroke
				(width 0.1)
				(type default)
			)
			(layer "F.Fab")
		)
		(fp_line
			(start 0.12065 -0.2794)
			(end 0.12065 -0.3048)
			(stroke
				(width 0.1)
				(type default)
			)
			(layer "F.Fab")
		)
		(fp_line
			(start 0.12065 -0.3048)
			(end 0.67945 -0.3048)
			(stroke
				(width 0.1)
				(type default)
			)
			(layer "F.Fab")
		)
		(fp_line
			(start 0.120396 0.3048)
			(end 0.120396 0.2794)
			(stroke
				(width 0.1)
				(type default)
			)
			(layer "F.Fab")
		)
		(fp_line
			(start 0.120396 0.2794)
			(end -0.12065 0.2794)
			(stroke
				(width 0.1)
				(type default)
			)
			(layer "F.Fab")
		)
		(fp_line
			(start -0.12065 0.3048)
			(end -0.67945 0.3048)
			(stroke
				(width 0.1)
				(type default)
			)
			(layer "F.Fab")
		)
		(fp_line
			(start -0.12065 0.2794)
			(end -0.12065 0.3048)
			(stroke
				(width 0.1)
				(type default)
			)
			(layer "F.Fab")
		)
		(fp_line
			(start -0.12065 -0.2794)
			(end 0.12065 -0.2794)
			(stroke
				(width 0.1)
				(type default)
			)
			(layer "F.Fab")
		)
		(fp_line
			(start -0.12065 -0.305054)
			(end -0.12065 -0.2794)
			(stroke
				(width 0.1)
				(type default)
			)
			(layer "F.Fab")
		)
		(fp_line
			(start -0.67945 0.3048)
			(end -0.67945 -0.305054)
			(stroke
				(width 0.1)
				(type default)
			)
			(layer "F.Fab")
		)
		(fp_line
			(start -0.67945 -0.305054)
			(end -0.12065 -0.305054)
			(stroke
				(width 0.1)
				(type default)
			)
			(layer "F.Fab")
		)
		(pad "1" smd circle
			(at -0.40005 0 180)
			(size 0 0)
			(layers "F.Cu" "F.Mask" "F.Paste")
			(net "SMB_BIC_I2C9_MUX1_SSD12_R_SDA")
		)
		(pad "2" smd circle
			(at 0.40005 0 180)
			(size 0 0)
			(layers "F.Cu" "F.Mask" "F.Paste")
			(net "SMB_BIC_I2C9_MUX1_SSD12_SDA")
		)
	)
)
